# T6G (Grand Teton) — schematic netlist excerpt (pin names and nets, part order shuffled) for the footprints in the layout excerpt that follows; sources: Cadence DE-HDL packaged netlist, KiCad conversion of 04192023_DAF0TMB3IC0_F0TG_MB_C_brd_V02_OCP.brd

C2213  Q_CAP  22UF 4V 20% X6S  pkg C0402  page 69 : A = PVDDCR_CPU1_P0 ; B = GND
R881  Q_RES  4.7K 5% CHIP  pkg 0201LF  page 342 : A = TEST1_RT_CPU1_P2 ; B = GND
C7022  Q_CAP  100UF 4V 20% X6S  pkg C0805  page 323 : A = P0V9_CPU1_RT0_2A ; B = GND

(kicad_pcb
	(version 20260206)
	(generator "pcbnew")
	(generator_version "10.0")
	(general
		(thickness 1.6)
		(legacy_teardrops no)
	)
	(paper "A4")
	(title_block
		(title "04192023_DAF0TMB3IC0_F0TG_MB_C_brd_V02_OCP.brd")
		(comment 1 "Grand Teton / footprints 6658-6660 of 8354")
	)
	(layers
		(0 "F.Cu" signal "TOP")
		(4 "In1.Cu" signal "GND")
		(6 "In2.Cu" signal "IN1")
		(8 "In3.Cu" signal "GND1")
		(10 "In4.Cu" signal "IN2")
		(12 "In5.Cu" signal "GND2")
		(14 "In6.Cu" signal "IN3")
		(16 "In7.Cu" signal "GND3")
		(18 "In8.Cu" signal "VCC")
		(20 "In9.Cu" signal "VCC1")
		(22 "In10.Cu" signal "GND4")
		(24 "In11.Cu" signal "IN4")
		(26 "In12.Cu" signal "GND5")
		(28 "In13.Cu" signal "IN5")
		(30 "In14.Cu" signal "GND6")
		(32 "In15.Cu" signal "IN6")
		(34 "In16.Cu" signal "GND7")
		(2 "B.Cu" signal "BOTTOM")
		(9 "F.Adhes" user "F.Adhesive")
		(11 "B.Adhes" user "B.Adhesive")
		(13 "F.Paste" user "Package Geometry/Pastemask Top")
		(15 "B.Paste" user "Package Geometry/Pastemask Bottom")
		(5 "F.SilkS" user "Ref Des/Silkscreen Top")
		(7 "B.SilkS" user "Ref Des/Silkscreen Bottom")
		(1 "F.Mask" user "Board Geometry/Soldermask Top")
		(3 "B.Mask" user "Board Geometry/Soldermask Bottom")
		(17 "Dwgs.User" user "User.Drawings")
		(19 "Cmts.User" user "User.Comments")
		(21 "Eco1.User" user "User.Eco1")
		(23 "Eco2.User" user "User.Eco2")
		(25 "Edge.Cuts" user "Board Geometry/Outline")
		(27 "Margin" user)
		(31 "F.CrtYd" user "Package Geometry/Place Bound Top")
		(29 "B.CrtYd" user "Package Geometry/Place Bound Bottom")
		(35 "F.Fab" user "Ref Des/Assembly Top")
		(33 "B.Fab" user "Ref Des/Assembly Bottom")
	)
	(footprint ""
		(layer "B.Cu")
		(at 142.893542 -384.66268 180)
		(property "Reference" "R881"
			(at 0 0 0)
			(layer "B.SilkS")
			(hide yes)
			(effects
				(font
					(size 1.27 1.27)
				)
				(justify mirror)
			)
		)
		(property "Value" ""
			(at 0 0 0)
			(layer "B.Fab")
			(effects
				(font
					(size 1.27 1.27)
				)
				(justify mirror)
			)
		)
		(duplicate_pad_numbers_are_jumpers no)
		(fp_line
			(start 0.32512 0.175006)
			(end 0.32512 -0.175006)
			(stroke
				(width 0.1)
				(type default)
			)
			(layer "B.Fab")
		)
		(fp_line
			(start 0.32512 -0.175006)
			(end -0.32512 -0.175006)
			(stroke
				(width 0.1)
				(type default)
			)
			(layer "B.Fab")
		)
		(fp_line
			(start -0.32512 0.175006)
			(end 0.32512 0.175006)
			(stroke
				(width 0.1)
				(type default)
			)
			(layer "B.Fab")
		)
		(fp_line
			(start -0.32512 -0.175006)
			(end -0.32512 0.175006)
			(stroke
				(width 0.1)
				(type default)
			)
			(layer "B.Fab")
		)
		(pad "1" smd rect
			(at 0.2667 0)
			(size 0.3048 0.381)
			(layers "B.Cu" "B.Mask" "B.Paste")
			(net "TEST1_RT_CPU1_P2")
		)
		(pad "2" smd rect
			(at -0.2667 0 180)
			(size 0.3048 0.381)
			(layers "B.Cu" "B.Mask" "B.Paste")
			(net "GND")
		)
	)
	(footprint ""
		(layer "B.Cu")
		(at 366.566958 -272.284952 180)
		(property "Reference" "C2213"
			(at 0 0 0)
			(layer "B.SilkS")
			(hide yes)
			(effects
				(font
					(size 1.27 1.27)
				)
				(justify mirror)
			)
		)
		(property "Value" ""
			(at 0 0 0)
			(layer "B.Fab")
			(effects
				(font
					(size 1.27 1.27)
				)
				(justify mirror)
			)
		)
		(duplicate_pad_numbers_are_jumpers no)
		(fp_line
			(start 0.7874 0.4064)
			(end 0.7874 -0.4064)
			(stroke
				(width 0.1524)
				(type default)
			)
			(layer "B.SilkS")
		)
		(fp_line
			(start 0.7874 -0.4064)
			(end -0.7874 -0.4064)
			(stroke
				(width 0.1524)
				(type default)
			)
			(layer "B.SilkS")
		)
		(fp_line
			(start -0.7874 0.4064)
			(end 0.7874 0.4064)
			(stroke
				(width 0.1524)
				(type default)
			)
			(layer "B.SilkS")
		)
		(fp_line
			(start -0.7874 -0.4064)
			(end -0.7874 0.4064)
			(stroke
				(width 0.1524)
				(type default)
			)
			(layer "B.SilkS")
		)
		(fp_line
			(start 0.67945 0.3048)
			(end 0.67945 -0.305054)
			(stroke
				(width 0.1)
				(type default)
			)
			(layer "B.Fab")
		)
		(fp_line
			(start 0.67945 -0.305054)
			(end 0.12065 -0.305054)
			(stroke
				(width 0.1)
				(type default)
			)
			(layer "B.Fab")
		)
		(fp_line
			(start 0.12065 0.3048)
			(end 0.67945 0.3048)
			(stroke
				(width 0.1)
				(type default)
			)
			(layer "B.Fab")
		)
		(fp_line
			(start 0.12065 0.2794)
			(end 0.12065 0.3048)
			(stroke
				(width 0.1)
				(type default)
			)
			(layer "B.Fab")
		)
		(fp_line
			(start 0.12065 -0.2794)
			(end -0.12065 -0.2794)
			(stroke
				(width 0.1)
				(type default)
			)
			(layer "B.Fab")
		)
		(fp_line
			(start 0.12065 -0.305054)
			(end 0.12065 -0.2794)
			(stroke
				(width 0.1)
				(type default)
			)
			(layer "B.Fab")
		)
		(fp_line
			(start -0.120396 0.3048)
			(end -0.120396 0.2794)
			(stroke
				(width 0.1)
				(type default)
			)
			(layer "B.Fab")
		)
		(fp_line
			(start -0.120396 0.2794)
			(end 0.12065 0.2794)
			(stroke
				(width 0.1)
				(type default)
			)
			(layer "B.Fab")
		)
		(fp_line
			(start -0.12065 -0.2794)
			(end -0.12065 -0.3048)
			(stroke
				(width 0.1)
				(type default)
			)
			(layer "B.Fab")
		)
		(fp_line
			(start -0.12065 -0.3048)
			(end -0.67945 -0.3048)
			(stroke
				(width 0.1)
				(type default)
			)
			(layer "B.Fab")
		)
		(fp_line
			(start -0.67945 0.3048)
			(end -0.120396 0.3048)
			(stroke
				(width 0.1)
				(type default)
			)
			(layer "B.Fab")
		)
		(fp_line
			(start -0.67945 -0.3048)
			(end -0.67945 0.3048)
			(stroke
				(width 0.1)
				(type default)
			)
			(layer "B.Fab")
		)
		(pad "1" smd circle
			(at 0.40005 0)
			(size 0 0)
			(layers "B.Cu" "B.Mask" "B.Paste")
			(net "PVDDCR_CPU1_P0")
		)
		(pad "2" smd circle
			(at -0.40005 0)
			(size 0 0)
			(layers "B.Cu" "B.Mask" "B.Paste")
			(net "GND")
		)
	)
	(footprint ""
		(layer "B.Cu")
		(at 45.928788 -381.6223)
		(property "Reference" "C7022"
			(at 0 0 0)
			(layer "B.SilkS")
			(hide yes)
			(effects
				(font
					(size 1.27 1.27)
				)
				(justify mirror)
			)
		)
		(property "Value" ""
			(at 0 0 0)
			(layer "B.Fab")
			(effects
				(font
					(size 1.27 1.27)
				)
				(justify mirror)
			)
		)
		(duplicate_pad_numbers_are_jumpers no)
		(fp_line
			(start -1.524 -0.762)
			(end -1.524 0.762)
			(stroke
				(width 0.1524)
				(type default)
			)
			(layer "B.SilkS")
		)
		(fp_line
			(start -1.524 0.762)
			(end 1.524 0.762)
			(stroke
				(width 0.1524)
				(type default)
			)
			(layer "B.SilkS")
		)
		(fp_line
			(start 1.524 -0.762)
			(end -1.524 -0.762)
			(stroke
				(width 0.1524)
				(type default)
			)
			(layer "B.SilkS")
		)
		(fp_line
			(start 1.524 0.762)
			(end 1.524 -0.762)
			(stroke
				(width 0.1524)
				(type default)
			)
			(layer "B.SilkS")
		)
		(fp_line
			(start -1.1049 -0.724916)
			(end 1.1049 -0.724916)
			(stroke
				(width 0.1)
				(type default)
			)
			(layer "B.Fab")
		)
		(fp_line
			(start -1.1049 0.724916)
			(end -1.1049 -0.724916)
			(stroke
				(width 0.1)
				(type default)
			)
			(layer "B.Fab")
		)
		(fp_line
			(start 1.1049 -0.724916)
			(end 1.1049 0.724916)
			(stroke
				(width 0.1)
				(type default)
			)
			(layer "B.Fab")
		)
		(fp_line
			(start 1.1049 0.724916)
			(end -1.1049 0.724916)
			(stroke
				(width 0.1)
				(type default)
			)
			(layer "B.Fab")
		)
		(pad "1" smd rect
			(at 0.889 0)
			(size 1.016 1.27)
			(layers "B.Cu" "B.Mask" "B.Paste")
			(net "P0V9_CPU1_RT0_2A")
		)
		(pad "2" smd rect
			(at -0.889 0)
			(size 1.016 1.27)
			(layers "B.Cu" "B.Mask" "B.Paste")
			(net "GND")
		)
	)
)
